# S9S_MB_2U (Grand Teton) — schematic netlist excerpt (pin names and nets, part order shuffled) for the footprints in the layout excerpt that follows; sources: Cadence DE-HDL packaged netlist, KiCad conversion of 03242023_DA0F0TMBIJ0_F0T_Motherboard_J_brd_V01_OCP.brd

PPQ2  MOSFET_NCH_1D3S  PSMNR58-30YLH EMPTY  pkg SOT1023  page 304
  \1\  = P12V_AUX
  \2\  = P12V_AUX
  \3\  = P12V_AUX
  \4\  = P12V_HSC_GATE_G6
  \5\  = P12V_MAIN_R

C957  Q_CAP_DIFFBUS  DIFF BUS_0.22UF 6.3V 20% X6S  pkg C0201  page 173 : \1\ = P5E_CPU0_PE2_TX_C_DP<4> ; \2\ = P5E_CPU0_PE2_TX_DP<4>
PC1191  Q_CAP  2.2UF 10V 10% X6S  pkg C0402  page 290 : A = PVCCFA_EHV_FIVRA_CPU1_VDD3 ; B = GND

(kicad_pcb
	(version 20260206)
	(generator "pcbnew")
	(generator_version "10.0")
	(general
		(thickness 1.6)
		(legacy_teardrops no)
	)
	(paper "A4")
	(title_block
		(title "03242023_DA0F0TMBIJ0_F0T_Motherboard_J_brd_V01_OCP.brd")
		(comment 1 "Grand Teton / footprints 1824-1826 of 6105")
	)
	(layers
		(0 "F.Cu" signal "TOP")
		(4 "In1.Cu" signal "GND")
		(6 "In2.Cu" signal "IN1")
		(8 "In3.Cu" signal "GND1")
		(10 "In4.Cu" signal "IN2")
		(12 "In5.Cu" signal "GND2")
		(14 "In6.Cu" signal "IN3")
		(16 "In7.Cu" signal "GND3")
		(18 "In8.Cu" signal "VCC")
		(20 "In9.Cu" signal "VCC1")
		(22 "In10.Cu" signal "GND4")
		(24 "In11.Cu" signal "IN4")
		(26 "In12.Cu" signal "GND5")
		(28 "In13.Cu" signal "IN5")
		(30 "In14.Cu" signal "GND6")
		(32 "In15.Cu" signal "IN6")
		(34 "In16.Cu" signal "GND7")
		(2 "B.Cu" signal "BOTTOM")
		(9 "F.Adhes" user "F.Adhesive")
		(11 "B.Adhes" user "B.Adhesive")
		(13 "F.Paste" user "Package Geometry/Pastemask Top")
		(15 "B.Paste" user "Package Geometry/Pastemask Bottom")
		(5 "F.SilkS" user "Ref Des/Silkscreen Top")
		(7 "B.SilkS" user "Ref Des/Silkscreen Bottom")
		(1 "F.Mask" user "Board Geometry/Soldermask Top")
		(3 "B.Mask" user "Board Geometry/Soldermask Bottom")
		(17 "Dwgs.User" user "User.Drawings")
		(19 "Cmts.User" user "User.Comments")
		(21 "Eco1.User" user "User.Eco1")
		(23 "Eco2.User" user "User.Eco2")
		(25 "Edge.Cuts" user "Board Geometry/Outline")
		(27 "Margin" user)
		(31 "F.CrtYd" user "Package Geometry/Place Bound Top")
		(29 "B.CrtYd" user "Package Geometry/Place Bound Bottom")
		(35 "F.Fab" user "Ref Des/Assembly Top")
		(33 "B.Fab" user "Ref Des/Assembly Bottom")
	)
	(footprint ""
		(layer "F.Cu")
		(at 248.22658 -398.78 90)
		(property "Reference" "PPQ2"
			(at -8.221472 -1.44272 0)
			(unlocked yes)
			(layer "F.SilkS")
			(effects
				(font
					(size 0.7874 0.5842)
					(thickness 0.1524)
				)
				(justify left)
			)
		)
		(property "Value" ""
			(at 0 0 90)
			(layer "F.Fab")
			(effects
				(font
					(size 1.27 1.27)
				)
			)
		)
		(duplicate_pad_numbers_are_jumpers no)
		(fp_line
			(start 2.350008 -2.649982)
			(end 2.350008 -2.4892)
			(stroke
				(width 0.1524)
				(type default)
			)
			(layer "F.SilkS")
		)
		(fp_line
			(start -2.350008 -2.649982)
			(end 2.350008 -2.649982)
			(stroke
				(width 0.1524)
				(type default)
			)
			(layer "F.SilkS")
		)
		(fp_line
			(start -2.350008 -2.4384)
			(end -2.350008 -2.649982)
			(stroke
				(width 0.1524)
				(type default)
			)
			(layer "F.SilkS")
		)
		(fp_line
			(start 2.350008 2.4892)
			(end 2.350008 2.649982)
			(stroke
				(width 0.1524)
				(type default)
			)
			(layer "F.SilkS")
		)
		(fp_line
			(start 2.350008 2.649982)
			(end -2.350008 2.649982)
			(stroke
				(width 0.1524)
				(type default)
			)
			(layer "F.SilkS")
		)
		(fp_line
			(start -2.350008 2.649982)
			(end -2.350008 2.413)
			(stroke
				(width 0.1524)
				(type default)
			)
			(layer "F.SilkS")
		)
		(fp_poly
			(pts
				(xy -3.717544 -1.905) (xy -4.758944 -2.3241) (xy -4.758944 -1.524)
			)
			(stroke
				(width 0)
				(type default)
			)
			(fill yes)
			(layer "F.SilkS")
		)
		(fp_line
			(start 2.350008 -2.649982)
			(end 2.350008 2.649982)
			(stroke
				(width 0.1)
				(type default)
			)
			(layer "F.Fab")
		)
		(fp_line
			(start -2.350008 -2.649982)
			(end 2.350008 -2.649982)
			(stroke
				(width 0.1)
				(type default)
			)
			(layer "F.Fab")
		)
		(fp_line
			(start 2.350008 2.649982)
			(end -2.350008 2.649982)
			(stroke
				(width 0.1)
				(type default)
			)
			(layer "F.Fab")
		)
		(fp_line
			(start -2.350008 2.649982)
			(end -2.350008 -2.649982)
			(stroke
				(width 0.1)
				(type default)
			)
			(layer "F.Fab")
		)
		(fp_poly
			(pts
				(xy -3.717544 -1.905) (xy -4.758944 -2.3241) (xy -4.758944 -1.524)
			)
			(stroke
				(width 0)
				(type default)
			)
			(fill yes)
			(layer "F.Fab")
		)
		(pad "1" smd rect
			(at -2.999994 -1.905)
			(size 0.7112 1.1684)
			(layers "F.Cu" "F.Mask" "F.Paste")
			(net "P12V_AUX")
		)
		(pad "2" smd rect
			(at -2.999994 -0.635)
			(size 0.7112 1.1684)
			(layers "F.Cu" "F.Mask" "F.Paste")
			(net "P12V_AUX")
		)
		(pad "3" smd rect
			(at -2.999994 0.635)
			(size 0.7112 1.1684)
			(layers "F.Cu" "F.Mask" "F.Paste")
			(net "P12V_AUX")
		)
		(pad "4" smd rect
			(at -2.999994 1.905)
			(size 0.7112 1.1684)
			(layers "F.Cu" "F.Mask" "F.Paste")
			(net "P12V_HSC_GATE_G6")
		)
		(pad "5" smd circle
			(at 0.925068 0)
			(size 0 0)
			(layers "F.Cu" "F.Mask" "F.Paste")
			(net "P12V_MAIN_R")
		)
		(zone
			(layer "F.Cu")
			(hatch none 0.5)
			(connect_pads
				(clearance 0)
			)
			(min_thickness 0.25)
			(keepout
				(tracks not_allowed)
				(vias allowed)
				(pads allowed)
				(copperpour not_allowed)
				(footprints allowed)
			)
			(placement
				(enabled no)
				(sheetname "")
			)
			(fill
				(thermal_gap 0.5)
				(thermal_bridge_width 0.5)
				(island_removal_mode 0)
			)
			(polygon
				(pts
					(xy 246.06758 -397.3322) (xy 250.38558 -397.3322) (xy 250.47702 -397.24076) (xy 250.86818 -397.24076)
					(xy 250.86818 -396.4305) (xy 245.58498 -396.4305) (xy 245.58498 -397.3322)
				)
			)
		)
	)
	(footprint ""
		(layer "F.Cu")
		(at 178.13782 -356.03053 90)
		(property "Reference" "PC1191"
			(at 0 0 90)
			(layer "F.SilkS")
			(hide yes)
			(effects
				(font
					(size 1.27 1.27)
				)
			)
		)
		(property "Value" ""
			(at 0 0 90)
			(layer "F.Fab")
			(effects
				(font
					(size 1.27 1.27)
				)
			)
		)
		(duplicate_pad_numbers_are_jumpers no)
		(fp_line
			(start 0.7874 -0.4064)
			(end 0.7874 0.4064)
			(stroke
				(width 0.1524)
				(type default)
			)
			(layer "F.SilkS")
		)
		(fp_line
			(start -0.7874 -0.4064)
			(end 0.7874 -0.4064)
			(stroke
				(width 0.1524)
				(type default)
			)
			(layer "F.SilkS")
		)
		(fp_line
			(start 0.7874 0.4064)
			(end -0.7874 0.4064)
			(stroke
				(width 0.1524)
				(type default)
			)
			(layer "F.SilkS")
		)
		(fp_line
			(start -0.7874 0.4064)
			(end -0.7874 -0.4064)
			(stroke
				(width 0.1524)
				(type default)
			)
			(layer "F.SilkS")
		)
		(fp_line
			(start -0.12065 -0.305054)
			(end -0.12065 -0.2794)
			(stroke
				(width 0.1)
				(type default)
			)
			(layer "F.Fab")
		)
		(fp_line
			(start -0.67945 -0.305054)
			(end -0.12065 -0.305054)
			(stroke
				(width 0.1)
				(type default)
			)
			(layer "F.Fab")
		)
		(fp_line
			(start 0.67945 -0.3048)
			(end 0.67945 0.3048)
			(stroke
				(width 0.1)
				(type default)
			)
			(layer "F.Fab")
		)
		(fp_line
			(start 0.12065 -0.3048)
			(end 0.67945 -0.3048)
			(stroke
				(width 0.1)
				(type default)
			)
			(layer "F.Fab")
		)
		(fp_line
			(start 0.12065 -0.2794)
			(end 0.12065 -0.3048)
			(stroke
				(width 0.1)
				(type default)
			)
			(layer "F.Fab")
		)
		(fp_line
			(start -0.12065 -0.2794)
			(end 0.12065 -0.2794)
			(stroke
				(width 0.1)
				(type default)
			)
			(layer "F.Fab")
		)
		(fp_line
			(start 0.120396 0.2794)
			(end -0.12065 0.2794)
			(stroke
				(width 0.1)
				(type default)
			)
			(layer "F.Fab")
		)
		(fp_line
			(start -0.12065 0.2794)
			(end -0.12065 0.3048)
			(stroke
				(width 0.1)
				(type default)
			)
			(layer "F.Fab")
		)
		(fp_line
			(start 0.67945 0.3048)
			(end 0.120396 0.3048)
			(stroke
				(width 0.1)
				(type default)
			)
			(layer "F.Fab")
		)
		(fp_line
			(start 0.120396 0.3048)
			(end 0.120396 0.2794)
			(stroke
				(width 0.1)
				(type default)
			)
			(layer "F.Fab")
		)
		(fp_line
			(start -0.12065 0.3048)
			(end -0.67945 0.3048)
			(stroke
				(width 0.1)
				(type default)
			)
			(layer "F.Fab")
		)
		(fp_line
			(start -0.67945 0.3048)
			(end -0.67945 -0.305054)
			(stroke
				(width 0.1)
				(type default)
			)
			(layer "F.Fab")
		)
		(pad "1" smd circle
			(at -0.40005 0 90)
			(size 0 0)
			(layers "F.Cu" "F.Mask" "F.Paste")
			(net "PVCCFA_EHV_FIVRA_CPU1_VDD3")
		)
		(pad "2" smd circle
			(at 0.40005 0 90)
			(size 0 0)
			(layers "F.Cu" "F.Mask" "F.Paste")
			(net "GND")
		)
	)
	(footprint ""
		(layer "F.Cu")
		(at 405.09317 -402.371052 -90)
		(property "Reference" "C957"
			(at 0 0 270)
			(layer "F.SilkS")
			(hide yes)
			(effects
				(font
					(size 1.27 1.27)
				)
			)
		)
		(property "Value" ""
			(at 0 0 270)
			(layer "F.Fab")
			(effects
				(font
					(size 1.27 1.27)
				)
			)
		)
		(duplicate_pad_numbers_are_jumpers no)
		(fp_line
			(start -0.299974 0.150114)
			(end -0.299974 -0.150114)
			(stroke
				(width 0.1)
				(type default)
			)
			(layer "F.Fab")
		)
		(fp_line
			(start 0.299974 0.150114)
			(end -0.299974 0.150114)
			(stroke
				(width 0.1)
				(type default)
			)
			(layer "F.Fab")
		)
		(fp_line
			(start -0.299974 -0.150114)
			(end 0.299974 -0.150114)
			(stroke
				(width 0.1)
				(type default)
			)
			(layer "F.Fab")
		)
		(fp_line
			(start 0.299974 -0.150114)
			(end 0.299974 0.150114)
			(stroke
				(width 0.1)
				(type default)
			)
			(layer "F.Fab")
		)
		(pad "1" smd rect
			(at -0.2667 0 270)
			(size 0.3048 0.381)
			(layers "F.Cu" "F.Mask" "F.Paste")
			(net "P5E_CPU0_PE2_TX_C_DP<4>")
		)
		(pad "2" smd rect
			(at 0.2667 0 270)
			(size 0.3048 0.381)
			(layers "F.Cu" "F.Mask" "F.Paste")
			(net "P5E_CPU0_PE2_TX_DP<4>")
		)
	)
)
